# BASEBOARD_FAB2 (Tioga Pass) — schematic netlist excerpt (pin names and nets, part order shuffled) for the footprints in the layout excerpt that follows; sources: Cadence DE-HDL packaged netlist, KiCad conversion of Wiwynn_Tioga_Pass_MB.brd

C6P11  CAP_A  0.1UF 16V 10% X7R  pkg 0402V  page 102 : A = P3V3_DB1200 ; B = GND
C7B16  CAP_A  22.0UF 4V 20% X6S  pkg 0603V  page 131 : A = P1V05_PCH_STBY ; B = GND
R1L14  RES  10.0 1% CHIP  pkg 0402  page 155 : A = LED_POSTCODE_6 ; B = LED_POSTCODE_6_R

(kicad_pcb
	(version 20260206)
	(generator "pcbnew")
	(generator_version "10.0")
	(general
		(thickness 1.6)
		(legacy_teardrops no)
	)
	(paper "A4")
	(title_block
		(title "Wiwynn_Tioga_Pass_MB.brd")
		(comment 1 "Tioga Pass / footprints 3444-3446 of 4770")
	)
	(layers
		(0 "F.Cu" signal "TOP")
		(4 "In1.Cu" signal "L2GND")
		(6 "In2.Cu" signal "L3")
		(8 "In3.Cu" signal "L4GND")
		(10 "In4.Cu" signal "L5")
		(12 "In5.Cu" signal "L6GND")
		(14 "In6.Cu" signal "L7VCC")
		(16 "In7.Cu" signal "L8VCC")
		(18 "In8.Cu" signal "L9GND")
		(20 "In9.Cu" signal "L10")
		(22 "In10.Cu" signal "L11GND")
		(24 "In11.Cu" signal "L12")
		(26 "In12.Cu" signal "L13GND")
		(2 "B.Cu" signal "BOTTOM")
		(9 "F.Adhes" user "F.Adhesive")
		(11 "B.Adhes" user "B.Adhesive")
		(13 "F.Paste" user "Package Geometry/Pastemask Top")
		(15 "B.Paste" user "Package Geometry/Pastemask Bottom")
		(5 "F.SilkS" user "Ref Des/Silkscreen Top")
		(7 "B.SilkS" user "Ref Des/Silkscreen Bottom")
		(1 "F.Mask" user "Board Geometry/Soldermask Top")
		(3 "B.Mask" user "Board Geometry/Soldermask Bottom")
		(17 "Dwgs.User" user "User.Drawings")
		(19 "Cmts.User" user "User.Comments")
		(21 "Eco1.User" user "User.Eco1")
		(23 "Eco2.User" user "User.Eco2")
		(25 "Edge.Cuts" user "Board Geometry/Outline")
		(27 "Margin" user)
		(31 "F.CrtYd" user "Package Geometry/Place Bound Top")
		(29 "B.CrtYd" user "Package Geometry/Place Bound Bottom")
		(35 "F.Fab" user "Ref Des/Assembly Top")
		(33 "B.Fab" user "Ref Des/Assembly Bottom")
	)
	(footprint ""
		(layer "B.Cu")
		(at 173.863 -80.645 -90)
		(property "Reference" "C6P11"
			(at 0 0 90)
			(layer "B.SilkS")
			(hide yes)
			(effects
				(font
					(size 1.27 1.27)
				)
				(justify mirror)
			)
		)
		(property "Value" ""
			(at 0 0 90)
			(layer "B.Fab")
			(effects
				(font
					(size 1.27 1.27)
				)
				(justify mirror)
			)
		)
		(duplicate_pad_numbers_are_jumpers no)
		(fp_poly
			(pts
				(xy -0.3048 -0.1016) (xy -0.3048 0.9906) (xy 0.3048 0.9906) (xy 0.3048 -0.1016)
			)
			(stroke
				(width 0)
				(type default)
			)
			(fill no)
			(layer "B.CrtYd")
		)
		(fp_line
			(start -0.3048 0.9906)
			(end -0.3048 -0.1016)
			(stroke
				(width 0.1)
				(type default)
			)
			(layer "B.Fab")
		)
		(fp_line
			(start 0.3048 0.9906)
			(end -0.3048 0.9906)
			(stroke
				(width 0.1)
				(type default)
			)
			(layer "B.Fab")
		)
		(fp_line
			(start -0.3048 -0.1016)
			(end 0.3048 -0.1016)
			(stroke
				(width 0.1)
				(type default)
			)
			(layer "B.Fab")
		)
		(fp_line
			(start 0.3048 -0.1016)
			(end 0.3048 0.9906)
			(stroke
				(width 0.1)
				(type default)
			)
			(layer "B.Fab")
		)
		(pad "1" smd rect
			(at 0 0 90)
			(size 0.508 0.508)
			(layers "B.Cu" "B.Mask" "B.Paste")
			(net "P3V3_DB1200")
		)
		(pad "2" smd rect
			(at 0 0.889 90)
			(size 0.508 0.508)
			(layers "B.Cu" "B.Mask" "B.Paste")
			(net "GND")
		)
		(zone
			(layer "B.Cu")
			(hatch none 0.5)
			(connect_pads
				(clearance 0)
			)
			(min_thickness 0.25)
			(keepout
				(tracks not_allowed)
				(vias allowed)
				(pads allowed)
				(copperpour not_allowed)
				(footprints allowed)
			)
			(placement
				(enabled no)
				(sheetname "")
			)
			(fill
				(thermal_gap 0.5)
				(thermal_bridge_width 0.5)
				(island_removal_mode 0)
			)
			(polygon
				(pts
					(xy 173.228 -80.391) (xy 173.228 -80.899) (xy 173.609 -80.899) (xy 173.609 -80.391)
				)
			)
		)
		(zone
			(layer "B.Cu")
			(hatch none 0.5)
			(connect_pads
				(clearance 0)
			)
			(min_thickness 0.25)
			(keepout
				(tracks allowed)
				(vias not_allowed)
				(pads allowed)
				(copperpour not_allowed)
				(footprints allowed)
			)
			(placement
				(enabled no)
				(sheetname "")
			)
			(fill
				(thermal_gap 0.5)
				(thermal_bridge_width 0.5)
				(island_removal_mode 0)
			)
			(polygon
				(pts
					(xy 173.609 -80.391) (xy 173.609 -80.899) (xy 173.228 -80.899) (xy 173.228 -80.391)
				)
			)
		)
	)
	(footprint ""
		(layer "B.Cu")
		(at 489.65739 -147.193 90)
		(property "Reference" "R1L14"
			(at 0 0 90)
			(layer "B.SilkS")
			(hide yes)
			(effects
				(font
					(size 1.27 1.27)
				)
				(justify mirror)
			)
		)
		(property "Value" ""
			(at 0 0 90)
			(layer "B.Fab")
			(effects
				(font
					(size 1.27 1.27)
				)
				(justify mirror)
			)
		)
		(duplicate_pad_numbers_are_jumpers no)
		(fp_poly
			(pts
				(xy 0.2794 -0.1016) (xy -0.2794 -0.1016) (xy -0.2794 0.9906) (xy 0.2794 0.9906)
			)
			(stroke
				(width 0)
				(type default)
			)
			(fill no)
			(layer "B.CrtYd")
		)
		(fp_line
			(start 0.2794 -0.1016)
			(end 0.2794 0.9906)
			(stroke
				(width 0.1)
				(type default)
			)
			(layer "B.Fab")
		)
		(fp_line
			(start -0.2794 -0.1016)
			(end 0.2794 -0.1016)
			(stroke
				(width 0.1)
				(type default)
			)
			(layer "B.Fab")
		)
		(fp_line
			(start 0.2794 0.9906)
			(end -0.2794 0.9906)
			(stroke
				(width 0.1)
				(type default)
			)
			(layer "B.Fab")
		)
		(fp_line
			(start -0.2794 0.9906)
			(end -0.2794 -0.1016)
			(stroke
				(width 0.1)
				(type default)
			)
			(layer "B.Fab")
		)
		(pad "1" smd rect
			(at 0 0 270)
			(size 0.508 0.508)
			(layers "B.Cu" "B.Mask" "B.Paste")
			(net "LED_POSTCODE_6")
		)
		(pad "2" smd rect
			(at 0 0.889 270)
			(size 0.508 0.508)
			(layers "B.Cu" "B.Mask" "B.Paste")
			(net "LED_POSTCODE_6_R")
		)
		(zone
			(layer "B.Cu")
			(hatch none 0.5)
			(connect_pads
				(clearance 0)
			)
			(min_thickness 0.25)
			(keepout
				(tracks allowed)
				(vias not_allowed)
				(pads allowed)
				(copperpour not_allowed)
				(footprints allowed)
			)
			(placement
				(enabled no)
				(sheetname "")
			)
			(fill
				(thermal_gap 0.5)
				(thermal_bridge_width 0.5)
				(island_removal_mode 0)
			)
			(polygon
				(pts
					(xy 489.91139 -147.447) (xy 489.91139 -146.939) (xy 490.29239 -146.939) (xy 490.29239 -147.447)
				)
			)
		)
		(zone
			(layer "B.Cu")
			(hatch none 0.5)
			(connect_pads
				(clearance 0)
			)
			(min_thickness 0.25)
			(keepout
				(tracks not_allowed)
				(vias allowed)
				(pads allowed)
				(copperpour not_allowed)
				(footprints allowed)
			)
			(placement
				(enabled no)
				(sheetname "")
			)
			(fill
				(thermal_gap 0.5)
				(thermal_bridge_width 0.5)
				(island_removal_mode 0)
			)
			(polygon
				(pts
					(xy 490.29239 -147.447) (xy 490.29239 -146.939) (xy 489.91139 -146.939) (xy 489.91139 -147.447)
				)
			)
		)
	)
	(footprint ""
		(layer "B.Cu")
		(at 400.43608 -141.224 180)
		(property "Reference" "C7B16"
			(at 0 0 0)
			(layer "B.SilkS")
			(hide yes)
			(effects
				(font
					(size 1.27 1.27)
				)
				(justify mirror)
			)
		)
		(property "Value" ""
			(at 0 0 0)
			(layer "B.Fab")
			(effects
				(font
					(size 1.27 1.27)
				)
				(justify mirror)
			)
		)
		(duplicate_pad_numbers_are_jumpers no)
		(fp_rect
			(start 0.4953 1.6002)
			(end -0.4953 -0.2032)
			(stroke
				(width 0)
				(type default)
			)
			(fill no)
			(layer "B.CrtYd")
		)
		(fp_line
			(start 0.4953 1.6002)
			(end 0.4953 -0.2032)
			(stroke
				(width 0.1)
				(type default)
			)
			(layer "B.Fab")
		)
		(fp_line
			(start 0.4953 -0.2032)
			(end -0.4953 -0.2032)
			(stroke
				(width 0.1)
				(type default)
			)
			(layer "B.Fab")
		)
		(fp_line
			(start -0.4953 1.6002)
			(end 0.4953 1.6002)
			(stroke
				(width 0.1)
				(type default)
			)
			(layer "B.Fab")
		)
		(fp_line
			(start -0.4953 -0.2032)
			(end -0.4953 1.6002)
			(stroke
				(width 0.1)
				(type default)
			)
			(layer "B.Fab")
		)
		(pad "1" smd rect
			(at 0 0)
			(size 0.762 0.889)
			(layers "B.Cu" "B.Mask" "B.Paste")
			(net "P1V05_PCH_STBY")
		)
		(pad "2" smd rect
			(at 0 1.397)
			(size 0.762 0.889)
			(layers "B.Cu" "B.Mask" "B.Paste")
			(net "GND")
		)
		(zone
			(layer "B.Cu")
			(hatch none 0.5)
			(connect_pads
				(clearance 0)
			)
			(min_thickness 0.25)
			(keepout
				(tracks not_allowed)
				(vias allowed)
				(pads allowed)
				(copperpour not_allowed)
				(footprints allowed)
			)
			(placement
				(enabled no)
				(sheetname "")
			)
			(fill
				(thermal_gap 0.5)
				(thermal_bridge_width 0.5)
				(island_removal_mode 0)
			)
			(polygon
				(pts
					(xy 400.05508 -142.1765) (xy 400.05508 -141.6685) (xy 400.81708 -141.6685) (xy 400.81708 -142.1765)
				)
			)
		)
	)
)
